(kicad_pcb
	(version 20260206)
	(generator "pcbnew")
	(generator_version "10.0")
	(general
		(thickness 1.6)
		(legacy_teardrops no)
	)
	(paper "A4")
	(title_block
		(title "01162023_DA0F0TEBIF0_F0T_Expander_BD_F_brd_V02_OCP.brd")
		(comment 1 "Grand Teton / footprints 4295-4300 of 9728")
	)
	(layers
		(0 "F.Cu" signal "TOP")
		(4 "In1.Cu" signal "GND")
		(6 "In2.Cu" signal "VCC")
		(8 "In3.Cu" signal "VCC1")
		(10 "In4.Cu" signal "GND1")
		(12 "In5.Cu" signal "IN1")
		(14 "In6.Cu" signal "GND2")
		(16 "In7.Cu" signal "IN2")
		(18 "In8.Cu" signal "GND3")
		(20 "In9.Cu" signal "IN3")
		(22 "In10.Cu" signal "GND4")
		(24 "In11.Cu" signal "IN4")
		(26 "In12.Cu" signal "GND5")
		(28 "In13.Cu" signal "IN5")
		(30 "In14.Cu" signal "GND6")
		(32 "In15.Cu" signal "IN6")
		(34 "In16.Cu" signal "GND7")
		(2 "B.Cu" signal "BOTTOM")
		(9 "F.Adhes" user "F.Adhesive")
		(11 "B.Adhes" user "B.Adhesive")
		(13 "F.Paste" user "Package Geometry/Pastemask Top")
		(15 "B.Paste" user "Package Geometry/Pastemask Bottom")
		(5 "F.SilkS" user "Ref Des/Silkscreen Top")
		(7 "B.SilkS" user "Ref Des/Silkscreen Bottom")
		(1 "F.Mask" user "Board Geometry/Soldermask Top")
		(3 "B.Mask" user "Board Geometry/Soldermask Bottom")
		(17 "Dwgs.User" user "User.Drawings")
		(19 "Cmts.User" user "User.Comments")
		(21 "Eco1.User" user "User.Eco1")
		(23 "Eco2.User" user "User.Eco2")
		(25 "Edge.Cuts" user "Board Geometry/Outline")
		(27 "Margin" user)
		(31 "F.CrtYd" user "Package Geometry/Place Bound Top")
		(29 "B.CrtYd" user "Package Geometry/Place Bound Bottom")
		(35 "F.Fab" user "Ref Des/Assembly Top")
		(33 "B.Fab" user "Ref Des/Assembly Bottom")
	)
	(footprint ""
		(layer "F.Cu")
		(at 55.357776 -27.006296 -90)
		(property "Reference" "PR6923"
			(at 0 0 270)
			(layer "F.SilkS")
			(hide yes)
			(effects
				(font
					(size 1.27 1.27)
				)
			)
		)
		(property "Value" ""
			(at 0 0 270)
			(layer "F.Fab")
			(effects
				(font
					(size 1.27 1.27)
				)
			)
		)
		(duplicate_pad_numbers_are_jumpers no)
		(fp_line
			(start -0.7874 0.4064)
			(end -0.7874 -0.4064)
			(stroke
				(width 0.1524)
				(type default)
			)
			(layer "F.SilkS")
		)
		(fp_line
			(start 0.7874 0.4064)
			(end -0.7874 0.4064)
			(stroke
				(width 0.1524)
				(type default)
			)
			(layer "F.SilkS")
		)
		(fp_line
			(start -0.7874 -0.4064)
			(end 0.7874 -0.4064)
			(stroke
				(width 0.1524)
				(type default)
			)
			(layer "F.SilkS")
		)
		(fp_line
			(start 0.7874 -0.4064)
			(end 0.7874 0.4064)
			(stroke
				(width 0.1524)
				(type default)
			)
			(layer "F.SilkS")
		)
		(fp_line
			(start -0.67945 0.3048)
			(end -0.67945 -0.305054)
			(stroke
				(width 0.1)
				(type default)
			)
			(layer "F.Fab")
		)
		(fp_line
			(start -0.12065 0.3048)
			(end -0.67945 0.3048)
			(stroke
				(width 0.1)
				(type default)
			)
			(layer "F.Fab")
		)
		(fp_line
			(start 0.120396 0.3048)
			(end 0.120396 0.2794)
			(stroke
				(width 0.1)
				(type default)
			)
			(layer "F.Fab")
		)
		(fp_line
			(start 0.67945 0.3048)
			(end 0.120396 0.3048)
			(stroke
				(width 0.1)
				(type default)
			)
			(layer "F.Fab")
		)
		(fp_line
			(start -0.12065 0.2794)
			(end -0.12065 0.3048)
			(stroke
				(width 0.1)
				(type default)
			)
			(layer "F.Fab")
		)
		(fp_line
			(start 0.120396 0.2794)
			(end -0.12065 0.2794)
			(stroke
				(width 0.1)
				(type default)
			)
			(layer "F.Fab")
		)
		(fp_line
			(start -0.12065 -0.2794)
			(end 0.12065 -0.2794)
			(stroke
				(width 0.1)
				(type default)
			)
			(layer "F.Fab")
		)
		(fp_line
			(start 0.12065 -0.2794)
			(end 0.12065 -0.3048)
			(stroke
				(width 0.1)
				(type default)
			)
			(layer "F.Fab")
		)
		(fp_line
			(start 0.12065 -0.3048)
			(end 0.67945 -0.3048)
			(stroke
				(width 0.1)
				(type default)
			)
			(layer "F.Fab")
		)
		(fp_line
			(start 0.67945 -0.3048)
			(end 0.67945 0.3048)
			(stroke
				(width 0.1)
				(type default)
			)
			(layer "F.Fab")
		)
		(fp_line
			(start -0.67945 -0.305054)
			(end -0.12065 -0.305054)
			(stroke
				(width 0.1)
				(type default)
			)
			(layer "F.Fab")
		)
		(fp_line
			(start -0.12065 -0.305054)
			(end -0.12065 -0.2794)
			(stroke
				(width 0.1)
				(type default)
			)
			(layer "F.Fab")
		)
		(pad "1" smd circle
			(at -0.40005 0 270)
			(size 0 0)
			(layers "F.Cu" "F.Mask" "F.Paste")
			(net "P3V3_SSD2_CO_MODE")
		)
		(pad "2" smd circle
			(at 0.40005 0 270)
			(size 0 0)
			(layers "F.Cu" "F.Mask" "F.Paste")
			(net "GND")
		)
	)
	(footprint ""
		(layer "F.Cu")
		(at 101.971094 -397.512286 -90)
		(property "Reference" "R5454"
			(at 0 0 270)
			(layer "F.SilkS")
			(hide yes)
			(effects
				(font
					(size 1.27 1.27)
				)
			)
		)
		(property "Value" ""
			(at 0 0 270)
			(layer "F.Fab")
			(effects
				(font
					(size 1.27 1.27)
				)
			)
		)
		(duplicate_pad_numbers_are_jumpers no)
		(fp_line
			(start -0.7874 0.4064)
			(end -0.7874 -0.4064)
			(stroke
				(width 0.1524)
				(type default)
			)
			(layer "F.SilkS")
		)
		(fp_line
			(start 0.7874 0.4064)
			(end -0.7874 0.4064)
			(stroke
				(width 0.1524)
				(type default)
			)
			(layer "F.SilkS")
		)
		(fp_line
			(start -0.7874 -0.4064)
			(end 0.7874 -0.4064)
			(stroke
				(width 0.1524)
				(type default)
			)
			(layer "F.SilkS")
		)
		(fp_line
			(start 0.7874 -0.4064)
			(end 0.7874 0.4064)
			(stroke
				(width 0.1524)
				(type default)
			)
			(layer "F.SilkS")
		)
		(fp_line
			(start -0.67945 0.3048)
			(end -0.67945 -0.305054)
			(stroke
				(width 0.1)
				(type default)
			)
			(layer "F.Fab")
		)
		(fp_line
			(start -0.12065 0.3048)
			(end -0.67945 0.3048)
			(stroke
				(width 0.1)
				(type default)
			)
			(layer "F.Fab")
		)
		(fp_line
			(start 0.120396 0.3048)
			(end 0.120396 0.2794)
			(stroke
				(width 0.1)
				(type default)
			)
			(layer "F.Fab")
		)
		(fp_line
			(start 0.67945 0.3048)
			(end 0.120396 0.3048)
			(stroke
				(width 0.1)
				(type default)
			)
			(layer "F.Fab")
		)
		(fp_line
			(start -0.12065 0.2794)
			(end -0.12065 0.3048)
			(stroke
				(width 0.1)
				(type default)
			)
			(layer "F.Fab")
		)
		(fp_line
			(start 0.120396 0.2794)
			(end -0.12065 0.2794)
			(stroke
				(width 0.1)
				(type default)
			)
			(layer "F.Fab")
		)
		(fp_line
			(start -0.12065 -0.2794)
			(end 0.12065 -0.2794)
			(stroke
				(width 0.1)
				(type default)
			)
			(layer "F.Fab")
		)
		(fp_line
			(start 0.12065 -0.2794)
			(end 0.12065 -0.3048)
			(stroke
				(width 0.1)
				(type default)
			)
			(layer "F.Fab")
		)
		(fp_line
			(start 0.12065 -0.3048)
			(end 0.67945 -0.3048)
			(stroke
				(width 0.1)
				(type default)
			)
			(layer "F.Fab")
		)
		(fp_line
			(start 0.67945 -0.3048)
			(end 0.67945 0.3048)
			(stroke
				(width 0.1)
				(type default)
			)
			(layer "F.Fab")
		)
		(fp_line
			(start -0.67945 -0.305054)
			(end -0.12065 -0.305054)
			(stroke
				(width 0.1)
				(type default)
			)
			(layer "F.Fab")
		)
		(fp_line
			(start -0.12065 -0.305054)
			(end -0.12065 -0.2794)
			(stroke
				(width 0.1)
				(type default)
			)
			(layer "F.Fab")
		)
		(pad "1" smd circle
			(at -0.40005 0 270)
			(size 0 0)
			(layers "F.Cu" "F.Mask" "F.Paste")
			(net "P3V3_AUX")
		)
		(pad "2" smd circle
			(at 0.40005 0 270)
			(size 0 0)
			(layers "F.Cu" "F.Mask" "F.Paste")
			(net "BIC_USB_HUB_OVCUR4")
		)
	)
	(footprint ""
		(layer "F.Cu")
		(at 170.956224 -32.848042 -90)
		(property "Reference" "R6066"
			(at 0 0 270)
			(layer "F.SilkS")
			(hide yes)
			(effects
				(font
					(size 1.27 1.27)
				)
			)
		)
		(property "Value" ""
			(at 0 0 270)
			(layer "F.Fab")
			(effects
				(font
					(size 1.27 1.27)
				)
			)
		)
		(duplicate_pad_numbers_are_jumpers no)
		(fp_line
			(start -0.7874 0.4064)
			(end -0.7874 -0.4064)
			(stroke
				(width 0.1524)
				(type default)
			)
			(layer "F.SilkS")
		)
		(fp_line
			(start 0.7874 0.4064)
			(end -0.7874 0.4064)
			(stroke
				(width 0.1524)
				(type default)
			)
			(layer "F.SilkS")
		)
		(fp_line
			(start -0.7874 -0.4064)
			(end 0.7874 -0.4064)
			(stroke
				(width 0.1524)
				(type default)
			)
			(layer "F.SilkS")
		)
		(fp_line
			(start 0.7874 -0.4064)
			(end 0.7874 0.4064)
			(stroke
				(width 0.1524)
				(type default)
			)
			(layer "F.SilkS")
		)
		(fp_line
			(start -0.67945 0.3048)
			(end -0.67945 -0.305054)
			(stroke
				(width 0.1)
				(type default)
			)
			(layer "F.Fab")
		)
		(fp_line
			(start -0.12065 0.3048)
			(end -0.67945 0.3048)
			(stroke
				(width 0.1)
				(type default)
			)
			(layer "F.Fab")
		)
		(fp_line
			(start 0.120396 0.3048)
			(end 0.120396 0.2794)
			(stroke
				(width 0.1)
				(type default)
			)
			(layer "F.Fab")
		)
		(fp_line
			(start 0.67945 0.3048)
			(end 0.120396 0.3048)
			(stroke
				(width 0.1)
				(type default)
			)
			(layer "F.Fab")
		)
		(fp_line
			(start -0.12065 0.2794)
			(end -0.12065 0.3048)
			(stroke
				(width 0.1)
				(type default)
			)
			(layer "F.Fab")
		)
		(fp_line
			(start 0.120396 0.2794)
			(end -0.12065 0.2794)
			(stroke
				(width 0.1)
				(type default)
			)
			(layer "F.Fab")
		)
		(fp_line
			(start -0.12065 -0.2794)
			(end 0.12065 -0.2794)
			(stroke
				(width 0.1)
				(type default)
			)
			(layer "F.Fab")
		)
		(fp_line
			(start 0.12065 -0.2794)
			(end 0.12065 -0.3048)
			(stroke
				(width 0.1)
				(type default)
			)
			(layer "F.Fab")
		)
		(fp_line
			(start 0.12065 -0.3048)
			(end 0.67945 -0.3048)
			(stroke
				(width 0.1)
				(type default)
			)
			(layer "F.Fab")
		)
		(fp_line
			(start 0.67945 -0.3048)
			(end 0.67945 0.3048)
			(stroke
				(width 0.1)
				(type default)
			)
			(layer "F.Fab")
		)
		(fp_line
			(start -0.67945 -0.305054)
			(end -0.12065 -0.305054)
			(stroke
				(width 0.1)
				(type default)
			)
			(layer "F.Fab")
		)
		(fp_line
			(start -0.12065 -0.305054)
			(end -0.12065 -0.2794)
			(stroke
				(width 0.1)
				(type default)
			)
			(layer "F.Fab")
		)
		(pad "1" smd circle
			(at -0.40005 0 270)
			(size 0 0)
			(layers "F.Cu" "F.Mask" "F.Paste")
			(net "SSD6_AUX_P3V3_EN_R")
		)
		(pad "2" smd circle
			(at 0.40005 0 270)
			(size 0 0)
			(layers "F.Cu" "F.Mask" "F.Paste")
			(net "P3V3_SSD6_CO_EN")
		)
	)
	(footprint ""
		(layer "F.Cu")
		(at 305.147218 -20.35556)
		(property "Reference" "C3948"
			(at 0 0 0)
			(layer "F.SilkS")
			(hide yes)
			(effects
				(font
					(size 1.27 1.27)
				)
			)
		)
		(property "Value" ""
			(at 0 0 0)
			(layer "F.Fab")
			(effects
				(font
					(size 1.27 1.27)
				)
			)
		)
		(duplicate_pad_numbers_are_jumpers no)
		(fp_line
			(start -0.7874 -0.4064)
			(end 0.7874 -0.4064)
			(stroke
				(width 0.1524)
				(type default)
			)
			(layer "F.SilkS")
		)
		(fp_line
			(start -0.7874 0.4064)
			(end -0.7874 -0.4064)
			(stroke
				(width 0.1524)
				(type default)
			)
			(layer "F.SilkS")
		)
		(fp_line
			(start 0.7874 -0.4064)
			(end 0.7874 0.4064)
			(stroke
				(width 0.1524)
				(type default)
			)
			(layer "F.SilkS")
		)
		(fp_line
			(start 0.7874 0.4064)
			(end -0.7874 0.4064)
			(stroke
				(width 0.1524)
				(type default)
			)
			(layer "F.SilkS")
		)
		(fp_line
			(start -0.67945 -0.305054)
			(end -0.12065 -0.305054)
			(stroke
				(width 0.1)
				(type default)
			)
			(layer "F.Fab")
		)
		(fp_line
			(start -0.67945 0.3048)
			(end -0.67945 -0.305054)
			(stroke
				(width 0.1)
				(type default)
			)
			(layer "F.Fab")
		)
		(fp_line
			(start -0.12065 -0.305054)
			(end -0.12065 -0.2794)
			(stroke
				(width 0.1)
				(type default)
			)
			(layer "F.Fab")
		)
		(fp_line
			(start -0.12065 -0.2794)
			(end 0.12065 -0.2794)
			(stroke
				(width 0.1)
				(type default)
			)
			(layer "F.Fab")
		)
		(fp_line
			(start -0.12065 0.2794)
			(end -0.12065 0.3048)
			(stroke
				(width 0.1)
				(type default)
			)
			(layer "F.Fab")
		)
		(fp_line
			(start -0.12065 0.3048)
			(end -0.67945 0.3048)
			(stroke
				(width 0.1)
				(type default)
			)
			(layer "F.Fab")
		)
		(fp_line
			(start 0.120396 0.2794)
			(end -0.12065 0.2794)
			(stroke
				(width 0.1)
				(type default)
			)
			(layer "F.Fab")
		)
		(fp_line
			(start 0.120396 0.3048)
			(end 0.120396 0.2794)
			(stroke
				(width 0.1)
				(type default)
			)
			(layer "F.Fab")
		)
		(fp_line
			(start 0.12065 -0.3048)
			(end 0.67945 -0.3048)
			(stroke
				(width 0.1)
				(type default)
			)
			(layer "F.Fab")
		)
		(fp_line
			(start 0.12065 -0.2794)
			(end 0.12065 -0.3048)
			(stroke
				(width 0.1)
				(type default)
			)
			(layer "F.Fab")
		)
		(fp_line
			(start 0.67945 -0.3048)
			(end 0.67945 0.3048)
			(stroke
				(width 0.1)
				(type default)
			)
			(layer "F.Fab")
		)
		(fp_line
			(start 0.67945 0.3048)
			(end 0.120396 0.3048)
			(stroke
				(width 0.1)
				(type default)
			)
			(layer "F.Fab")
		)
		(pad "1" smd circle
			(at -0.40005 0)
			(size 0 0)
			(layers "F.Cu" "F.Mask" "F.Paste")
			(net "P12V_SSD10")
		)
		(pad "2" smd circle
			(at 0.40005 0)
			(size 0 0)
			(layers "F.Cu" "F.Mask" "F.Paste")
			(net "GND")
		)
	)
	(footprint ""
		(layer "F.Cu")
		(at 310.443626 -48.93691 180)
		(property "Reference" "R622"
			(at 0 0 180)
			(layer "F.SilkS")
			(hide yes)
			(effects
				(font
					(size 1.27 1.27)
				)
			)
		)
		(property "Value" ""
			(at 0 0 180)
			(layer "F.Fab")
			(effects
				(font
					(size 1.27 1.27)
				)
			)
		)
		(duplicate_pad_numbers_are_jumpers no)
		(fp_line
			(start 0.7874 0.4064)
			(end -0.7874 0.4064)
			(stroke
				(width 0.1524)
				(type default)
			)
			(layer "F.SilkS")
		)
		(fp_line
			(start 0.7874 -0.4064)
			(end 0.7874 0.4064)
			(stroke
				(width 0.1524)
				(type default)
			)
			(layer "F.SilkS")
		)
		(fp_line
			(start -0.7874 0.4064)
			(end -0.7874 -0.4064)
			(stroke
				(width 0.1524)
				(type default)
			)
			(layer "F.SilkS")
		)
		(fp_line
			(start -0.7874 -0.4064)
			(end 0.7874 -0.4064)
			(stroke
				(width 0.1524)
				(type default)
			)
			(layer "F.SilkS")
		)
		(fp_line
			(start 0.67945 0.3048)
			(end 0.120396 0.3048)
			(stroke
				(width 0.1)
				(type default)
			)
			(layer "F.Fab")
		)
		(fp_line
			(start 0.67945 -0.3048)
			(end 0.67945 0.3048)
			(stroke
				(width 0.1)
				(type default)
			)
			(layer "F.Fab")
		)
		(fp_line
			(start 0.12065 -0.2794)
			(end 0.12065 -0.3048)
			(stroke
				(width 0.1)
				(type default)
			)
			(layer "F.Fab")
		)
		(fp_line
			(start 0.12065 -0.3048)
			(end 0.67945 -0.3048)
			(stroke
				(width 0.1)
				(type default)
			)
			(layer "F.Fab")
		)
		(fp_line
			(start 0.120396 0.3048)
			(end 0.120396 0.2794)
			(stroke
				(width 0.1)
				(type default)
			)
			(layer "F.Fab")
		)
		(fp_line
			(start 0.120396 0.2794)
			(end -0.12065 0.2794)
			(stroke
				(width 0.1)
				(type default)
			)
			(layer "F.Fab")
		)
		(fp_line
			(start -0.12065 0.3048)
			(end -0.67945 0.3048)
			(stroke
				(width 0.1)
				(type default)
			)
			(layer "F.Fab")
		)
		(fp_line
			(start -0.12065 0.2794)
			(end -0.12065 0.3048)
			(stroke
				(width 0.1)
				(type default)
			)
			(layer "F.Fab")
		)
		(fp_line
			(start -0.12065 -0.2794)
			(end 0.12065 -0.2794)
			(stroke
				(width 0.1)
				(type default)
			)
			(layer "F.Fab")
		)
		(fp_line
			(start -0.12065 -0.305054)
			(end -0.12065 -0.2794)
			(stroke
				(width 0.1)
				(type default)
			)
			(layer "F.Fab")
		)
		(fp_line
			(start -0.67945 0.3048)
			(end -0.67945 -0.305054)
			(stroke
				(width 0.1)
				(type default)
			)
			(layer "F.Fab")
		)
		(fp_line
			(start -0.67945 -0.305054)
			(end -0.12065 -0.305054)
			(stroke
				(width 0.1)
				(type default)
			)
			(layer "F.Fab")
		)
		(pad "1" smd circle
			(at -0.40005 0 180)
			(size 0 0)
			(layers "F.Cu" "F.Mask" "F.Paste")
			(net "SMB_BIC_I2C6_MUX_SSD_8_15_ADC_R_SDA")
		)
		(pad "2" smd circle
			(at 0.40005 0 180)
			(size 0 0)
			(layers "F.Cu" "F.Mask" "F.Paste")
			(net "SMB_SSD10_ADC_SDA")
		)
	)
	(footprint ""
		(layer "F.Cu")
		(at 208.377282 -112.112806)
		(property "Reference" "PC789"
			(at 0 0 0)
			(layer "F.SilkS")
			(hide yes)
			(effects
				(font
					(size 1.27 1.27)
				)
			)
		)
		(property "Value" ""
			(at 0 0 0)
			(layer "F.Fab")
			(effects
				(font
					(size 1.27 1.27)
				)
			)
		)
		(duplicate_pad_numbers_are_jumpers no)
		(fp_line
			(start -0.7874 -0.4064)
			(end 0.7874 -0.4064)
			(stroke
				(width 0.1524)
				(type default)
			)
			(layer "F.SilkS")
		)
		(fp_line
			(start -0.7874 0.4064)
			(end -0.7874 -0.4064)
			(stroke
				(width 0.1524)
				(type default)
			)
			(layer "F.SilkS")
		)
		(fp_line
			(start 0.7874 -0.4064)
			(end 0.7874 0.4064)
			(stroke
				(width 0.1524)
				(type default)
			)
			(layer "F.SilkS")
		)
		(fp_line
			(start 0.7874 0.4064)
			(end -0.7874 0.4064)
			(stroke
				(width 0.1524)
				(type default)
			)
			(layer "F.SilkS")
		)
		(fp_line
			(start -0.67945 -0.305054)
			(end -0.12065 -0.305054)
			(stroke
				(width 0.1)
				(type default)
			)
			(layer "F.Fab")
		)
		(fp_line
			(start -0.67945 0.3048)
			(end -0.67945 -0.305054)
			(stroke
				(width 0.1)
				(type default)
			)
			(layer "F.Fab")
		)
		(fp_line
			(start -0.12065 -0.305054)
			(end -0.12065 -0.2794)
			(stroke
				(width 0.1)
				(type default)
			)
			(layer "F.Fab")
		)
		(fp_line
			(start -0.12065 -0.2794)
			(end 0.12065 -0.2794)
			(stroke
				(width 0.1)
				(type default)
			)
			(layer "F.Fab")
		)
		(fp_line
			(start -0.12065 0.2794)
			(end -0.12065 0.3048)
			(stroke
				(width 0.1)
				(type default)
			)
			(layer "F.Fab")
		)
		(fp_line
			(start -0.12065 0.3048)
			(end -0.67945 0.3048)
			(stroke
				(width 0.1)
				(type default)
			)
			(layer "F.Fab")
		)
		(fp_line
			(start 0.120396 0.2794)
			(end -0.12065 0.2794)
			(stroke
				(width 0.1)
				(type default)
			)
			(layer "F.Fab")
		)
		(fp_line
			(start 0.120396 0.3048)
			(end 0.120396 0.2794)
			(stroke
				(width 0.1)
				(type default)
			)
			(layer "F.Fab")
		)
		(fp_line
			(start 0.12065 -0.3048)
			(end 0.67945 -0.3048)
			(stroke
				(width 0.1)
				(type default)
			)
			(layer "F.Fab")
		)
		(fp_line
			(start 0.12065 -0.2794)
			(end 0.12065 -0.3048)
			(stroke
				(width 0.1)
				(type default)
			)
			(layer "F.Fab")
		)
		(fp_line
			(start 0.67945 -0.3048)
			(end 0.67945 0.3048)
			(stroke
				(width 0.1)
				(type default)
			)
			(layer "F.Fab")
		)
		(fp_line
			(start 0.67945 0.3048)
			(end 0.120396 0.3048)
			(stroke
				(width 0.1)
				(type default)
			)
			(layer "F.Fab")
		)
		(pad "1" smd circle
			(at -0.40005 0)
			(size 0 0)
			(layers "F.Cu" "F.Mask" "F.Paste")
			(net "P3V3_AUX")
		)
		(pad "2" smd circle
			(at 0.40005 0)
			(size 0 0)
			(layers "F.Cu" "F.Mask" "F.Paste")
			(net "GND")
		)
	)
)
